(kicad_pcb
	(version 20260206)
	(generator "pcbnew")
	(generator_version "10.0")
	(general
		(thickness 1.6)
		(legacy_teardrops no)
	)
	(paper "A4")
	(title_block
		(title "baseboard — 13948-1b.1110WZS1818.brd")
		(comment 1 "Honey Badger (Wiwynn) / footprints 1126-1133 of 2523")
	)
	(layers
		(0 "F.Cu" signal "TOP")
		(4 "In1.Cu" signal "L2GND")
		(6 "In2.Cu" signal "L3")
		(8 "In3.Cu" signal "L4VCC")
		(10 "In4.Cu" signal "L5VCC")
		(12 "In5.Cu" signal "L6")
		(14 "In6.Cu" signal "L7GND")
		(2 "B.Cu" signal "BOTTOM")
		(9 "F.Adhes" user "F.Adhesive")
		(11 "B.Adhes" user "B.Adhesive")
		(13 "F.Paste" user "Package Geometry/Pastemask Top")
		(15 "B.Paste" user "Package Geometry/Pastemask Bottom")
		(5 "F.SilkS" user "Ref Des/Silkscreen Top")
		(7 "B.SilkS" user "Ref Des/Silkscreen Bottom")
		(1 "F.Mask" user "Board Geometry/Soldermask Top")
		(3 "B.Mask" user "Board Geometry/Soldermask Bottom")
		(17 "Dwgs.User" user "User.Drawings")
		(19 "Cmts.User" user "User.Comments")
		(21 "Eco1.User" user "User.Eco1")
		(23 "Eco2.User" user "User.Eco2")
		(25 "Edge.Cuts" user "Board Geometry/Outline")
		(27 "Margin" user)
		(31 "F.CrtYd" user "Package Geometry/Place Bound Top")
		(29 "B.CrtYd" user "Package Geometry/Place Bound Bottom")
		(35 "F.Fab" user "Ref Des/Assembly Top")
		(33 "B.Fab" user "Ref Des/Assembly Bottom")
	)
	(footprint ""
		(layer "F.Cu")
		(at 198.755 -91.821 -90)
		(property "Reference" "PC235"
			(at 0 0 270)
			(layer "F.SilkS")
			(hide yes)
			(effects
				(font
					(size 1.27 1.27)
				)
			)
		)
		(property "Value" "SC22U6D3V5MX-2GP"
			(at -0.0762 -6.1214 270)
			(unlocked yes)
			(layer "F.Fab")
			(hide yes)
			(effects
				(font
					(size 1.016 1.016)
					(thickness 0.1524)
				)
			)
		)
		(property "Device Type" "C805H58"
			(at -0.0762 -8.1534 270)
			(unlocked yes)
			(layer "F.Fab")
			(hide yes)
			(effects
				(font
					(size 1.016 1.016)
					(thickness 0.1524)
				)
			)
		)
		(duplicate_pad_numbers_are_jumpers no)
		(fp_line
			(start 0.635 0)
			(end -0.635 0)
			(stroke
				(width 0.508)
				(type default)
			)
			(layer "F.SilkS")
		)
		(fp_rect
			(start -0.9652 1.778)
			(end 0.9652 -1.778)
			(stroke
				(width 0)
				(type default)
			)
			(fill no)
			(layer "F.CrtYd")
		)
		(fp_poly
			(pts
				(xy -0.9652 -1.778) (xy 0.9652 -1.778) (xy 0.9652 1.778) (xy -0.9652 1.778)
			)
			(stroke
				(width 0)
				(type default)
			)
			(fill no)
			(layer "F.Fab")
		)
		(pad "1" smd rect
			(at 0 -0.9652 270)
			(size 1.397 1.143)
			(layers "F.Cu" "F.Mask" "F.Paste")
			(net "P1V5_E")
		)
		(pad "2" smd rect
			(at 0 0.9652 270)
			(size 1.397 1.143)
			(layers "F.Cu" "F.Mask" "F.Paste")
			(net "GND")
		)
	)
	(footprint ""
		(layer "F.Cu")
		(at 219.41028 -91.02852)
		(property "Reference" "SR928"
			(at 0 0 0)
			(layer "F.SilkS")
			(hide yes)
			(effects
				(font
					(size 1.27 1.27)
				)
			)
		)
		(property "Value" "0R2J-2-GP"
			(at 0.064008 -3.993896 0)
			(unlocked yes)
			(layer "F.Fab")
			(hide yes)
			(effects
				(font
					(size 1.016 1.016)
					(thickness 0.1524)
				)
			)
		)
		(property "Device Type" "R402H16"
			(at 0.064008 -5.517896 0)
			(unlocked yes)
			(layer "F.Fab")
			(hide yes)
			(effects
				(font
					(size 1.016 1.016)
					(thickness 0.1524)
				)
			)
		)
		(duplicate_pad_numbers_are_jumpers no)
		(fp_line
			(start -0.508 -0.9398)
			(end -0.508 0.9398)
			(stroke
				(width 0.1524)
				(type default)
			)
			(layer "F.SilkS")
		)
		(fp_line
			(start 0.508 -0.9398)
			(end -0.508 -0.9398)
			(stroke
				(width 0.1524)
				(type default)
			)
			(layer "F.SilkS")
		)
		(fp_rect
			(start -0.508 0.9398)
			(end 0.508 -0.9398)
			(stroke
				(width 0)
				(type default)
			)
			(fill no)
			(layer "F.CrtYd")
		)
		(fp_rect
			(start -0.508 0.9398)
			(end 0.508 -0.9398)
			(stroke
				(width 0)
				(type default)
			)
			(fill no)
			(layer "F.Fab")
		)
		(pad "1" smd custom
			(at 0 -0.4445)
			(size 0.1397 0.1397)
			(layers "F.Cu" "F.Mask" "F.Paste")
			(net "IOC_UART_RX")
			(options
				(clearance outline)
				(anchor circle)
			)
			(primitives
				(gr_poly
					(pts
						(arc
							(start -0.1778 -0.2794)
							(mid -0.249642 -0.249642)
							(end -0.2794 -0.1778)
						)
						(arc
							(start -0.2794 0.1778)
							(mid -0.249642 0.249642)
							(end -0.1778 0.2794)
						)
						(arc
							(start 0.1778 0.2794)
							(mid 0.249642 0.249642)
							(end 0.2794 0.1778)
						)
						(arc
							(start 0.2794 -0.1778)
							(mid 0.249642 -0.249642)
							(end 0.1778 -0.2794)
						)
					)
					(width 0)
					(fill yes)
				)
			)
		)
		(pad "2" smd custom
			(at 0 0.4445)
			(size 0.1397 0.1397)
			(layers "F.Cu" "F.Mask" "F.Paste")
			(net "IOC_UART_R_RX")
			(options
				(clearance outline)
				(anchor circle)
			)
			(primitives
				(gr_poly
					(pts
						(arc
							(start -0.1778 -0.2794)
							(mid -0.249642 -0.249642)
							(end -0.2794 -0.1778)
						)
						(arc
							(start -0.2794 0.1778)
							(mid -0.249642 0.249642)
							(end -0.1778 0.2794)
						)
						(arc
							(start 0.1778 0.2794)
							(mid 0.249642 0.249642)
							(end 0.2794 0.1778)
						)
						(arc
							(start 0.2794 -0.1778)
							(mid 0.249642 -0.249642)
							(end 0.1778 -0.2794)
						)
					)
					(width 0)
					(fill yes)
				)
			)
		)
	)
	(footprint ""
		(layer "F.Cu")
		(at 233.426 -13.589)
		(property "Reference" "R544"
			(at 0 0 0)
			(layer "F.SilkS")
			(hide yes)
			(effects
				(font
					(size 1.27 1.27)
				)
			)
		)
		(property "Value" "1KR2F-3-GP"
			(at 0.064008 -3.993896 0)
			(unlocked yes)
			(layer "F.Fab")
			(hide yes)
			(effects
				(font
					(size 1.016 1.016)
					(thickness 0.1524)
				)
			)
		)
		(property "Device Type" "R402H16"
			(at 0.064008 -5.517896 0)
			(unlocked yes)
			(layer "F.Fab")
			(hide yes)
			(effects
				(font
					(size 1.016 1.016)
					(thickness 0.1524)
				)
			)
		)
		(duplicate_pad_numbers_are_jumpers no)
		(fp_line
			(start -0.508 -0.9398)
			(end -0.508 0.9398)
			(stroke
				(width 0.1524)
				(type default)
			)
			(layer "F.SilkS")
		)
		(fp_line
			(start 0.508 -0.9398)
			(end -0.508 -0.9398)
			(stroke
				(width 0.1524)
				(type default)
			)
			(layer "F.SilkS")
		)
		(fp_rect
			(start -0.508 0.9398)
			(end 0.508 -0.9398)
			(stroke
				(width 0)
				(type default)
			)
			(fill no)
			(layer "F.CrtYd")
		)
		(fp_rect
			(start -0.508 0.9398)
			(end 0.508 -0.9398)
			(stroke
				(width 0)
				(type default)
			)
			(fill no)
			(layer "F.Fab")
		)
		(pad "1" smd custom
			(at 0 -0.4445)
			(size 0.1397 0.1397)
			(layers "F.Cu" "F.Mask" "F.Paste")
			(net "ENCLO_LED_RED_D")
			(options
				(clearance outline)
				(anchor circle)
			)
			(primitives
				(gr_poly
					(pts
						(arc
							(start -0.1778 -0.2794)
							(mid -0.249642 -0.249642)
							(end -0.2794 -0.1778)
						)
						(arc
							(start -0.2794 0.1778)
							(mid -0.249642 0.249642)
							(end -0.1778 0.2794)
						)
						(arc
							(start 0.1778 0.2794)
							(mid 0.249642 0.249642)
							(end 0.2794 0.1778)
						)
						(arc
							(start 0.2794 -0.1778)
							(mid 0.249642 -0.249642)
							(end 0.1778 -0.2794)
						)
					)
					(width 0)
					(fill yes)
				)
			)
		)
		(pad "2" smd custom
			(at 0 0.4445)
			(size 0.1397 0.1397)
			(layers "F.Cu" "F.Mask" "F.Paste")
			(net "P3V3_STBY")
			(options
				(clearance outline)
				(anchor circle)
			)
			(primitives
				(gr_poly
					(pts
						(arc
							(start -0.1778 -0.2794)
							(mid -0.249642 -0.249642)
							(end -0.2794 -0.1778)
						)
						(arc
							(start -0.2794 0.1778)
							(mid -0.249642 0.249642)
							(end -0.1778 0.2794)
						)
						(arc
							(start 0.1778 0.2794)
							(mid 0.249642 0.249642)
							(end 0.2794 0.1778)
						)
						(arc
							(start 0.2794 -0.1778)
							(mid 0.249642 -0.249642)
							(end 0.1778 -0.2794)
						)
					)
					(width 0)
					(fill yes)
				)
			)
		)
	)
	(footprint ""
		(layer "F.Cu")
		(at 216.272872 -175.586136 90)
		(property "Reference" "R495"
			(at 0 0 90)
			(layer "F.SilkS")
			(hide yes)
			(effects
				(font
					(size 1.27 1.27)
				)
			)
		)
		(property "Value" "51R2010F-GP"
			(at 0.254 -8.0772 90)
			(unlocked yes)
			(layer "F.Fab")
			(hide yes)
			(effects
				(font
					(size 1.016 1.016)
					(thickness 0.1524)
				)
			)
		)
		(property "Device Type" "R2010H28"
			(at 0.254 -9.6774 90)
			(unlocked yes)
			(layer "F.Fab")
			(hide yes)
			(effects
				(font
					(size 1.016 1.016)
					(thickness 0.1524)
				)
			)
		)
		(duplicate_pad_numbers_are_jumpers no)
		(fp_line
			(start 1.651 -3.302)
			(end -1.651 -3.302)
			(stroke
				(width 0.1524)
				(type default)
			)
			(layer "F.SilkS")
		)
		(fp_line
			(start -1.651 -3.302)
			(end -1.651 3.302)
			(stroke
				(width 0.1524)
				(type default)
			)
			(layer "F.SilkS")
		)
		(fp_line
			(start 1.651 3.302)
			(end 1.651 -3.302)
			(stroke
				(width 0.1524)
				(type default)
			)
			(layer "F.SilkS")
		)
		(fp_line
			(start -1.651 3.302)
			(end 1.651 3.302)
			(stroke
				(width 0.1524)
				(type default)
			)
			(layer "F.SilkS")
		)
		(fp_rect
			(start -1.7272 -3.3782)
			(end 1.7272 3.3782)
			(stroke
				(width 0)
				(type default)
			)
			(fill no)
			(layer "F.CrtYd")
		)
		(fp_poly
			(pts
				(xy 1.7272 3.3782) (xy 1.7272 -3.3782) (xy -1.7272 -3.3782) (xy -1.7272 3.3782)
			)
			(stroke
				(width 0)
				(type default)
			)
			(fill no)
			(layer "F.Fab")
		)
		(pad "1" smd rect
			(at 0 -2.3495 90)
			(size 2.794 1.143)
			(layers "F.Cu" "F.Mask" "F.Paste")
			(net "P3V3_STBY")
		)
		(pad "2" smd rect
			(at 0 2.3495 90)
			(size 2.794 1.143)
			(layers "F.Cu" "F.Mask" "F.Paste")
			(net "HB_EXP_TO_BMC")
		)
	)
	(footprint ""
		(layer "F.Cu")
		(at 184.404 -219.456 -90)
		(property "Reference" "R2054"
			(at 0 0 270)
			(layer "F.SilkS")
			(hide yes)
			(effects
				(font
					(size 1.27 1.27)
				)
			)
		)
		(property "Value" "4K7R2F-GP"
			(at 0.064008 -3.993896 270)
			(unlocked yes)
			(layer "F.Fab")
			(hide yes)
			(effects
				(font
					(size 1.016 1.016)
					(thickness 0.1524)
				)
			)
		)
		(property "Device Type" "R402H16"
			(at 0.064008 -5.517896 270)
			(unlocked yes)
			(layer "F.Fab")
			(hide yes)
			(effects
				(font
					(size 1.016 1.016)
					(thickness 0.1524)
				)
			)
		)
		(duplicate_pad_numbers_are_jumpers no)
		(fp_line
			(start -0.508 -0.9398)
			(end -0.508 0.9398)
			(stroke
				(width 0.1524)
				(type default)
			)
			(layer "F.SilkS")
		)
		(fp_line
			(start 0.508 -0.9398)
			(end -0.508 -0.9398)
			(stroke
				(width 0.1524)
				(type default)
			)
			(layer "F.SilkS")
		)
		(fp_rect
			(start -0.508 0.9398)
			(end 0.508 -0.9398)
			(stroke
				(width 0)
				(type default)
			)
			(fill no)
			(layer "F.CrtYd")
		)
		(fp_rect
			(start -0.508 0.9398)
			(end 0.508 -0.9398)
			(stroke
				(width 0)
				(type default)
			)
			(fill no)
			(layer "F.Fab")
		)
		(pad "1" smd custom
			(at 0 -0.4445 270)
			(size 0.1397 0.1397)
			(layers "F.Cu" "F.Mask" "F.Paste")
			(net "FM_BMC_READY_N")
			(options
				(clearance outline)
				(anchor circle)
			)
			(primitives
				(gr_poly
					(pts
						(arc
							(start -0.1778 -0.2794)
							(mid -0.249642 -0.249642)
							(end -0.2794 -0.1778)
						)
						(arc
							(start -0.2794 0.1778)
							(mid -0.249642 0.249642)
							(end -0.1778 0.2794)
						)
						(arc
							(start 0.1778 0.2794)
							(mid 0.249642 0.249642)
							(end 0.2794 0.1778)
						)
						(arc
							(start 0.2794 -0.1778)
							(mid 0.249642 -0.249642)
							(end 0.1778 -0.2794)
						)
					)
					(width 0)
					(fill yes)
				)
			)
		)
		(pad "2" smd custom
			(at 0 0.4445 270)
			(size 0.1397 0.1397)
			(layers "F.Cu" "F.Mask" "F.Paste")
			(net "P3V3_STBY")
			(options
				(clearance outline)
				(anchor circle)
			)
			(primitives
				(gr_poly
					(pts
						(arc
							(start -0.1778 -0.2794)
							(mid -0.249642 -0.249642)
							(end -0.2794 -0.1778)
						)
						(arc
							(start -0.2794 0.1778)
							(mid -0.249642 0.249642)
							(end -0.1778 0.2794)
						)
						(arc
							(start 0.1778 0.2794)
							(mid 0.249642 0.249642)
							(end 0.2794 0.1778)
						)
						(arc
							(start 0.2794 -0.1778)
							(mid 0.249642 -0.249642)
							(end 0.1778 -0.2794)
						)
					)
					(width 0)
					(fill yes)
				)
			)
		)
	)
	(footprint ""
		(layer "F.Cu")
		(at 315.468 -151.892 -90)
		(property "Reference" "R5201"
			(at 0 0 270)
			(layer "F.SilkS")
			(hide yes)
			(effects
				(font
					(size 1.27 1.27)
				)
			)
		)
		(property "Value" "0R2J-2-GP"
			(at 0.064008 -3.993896 270)
			(unlocked yes)
			(layer "F.Fab")
			(hide yes)
			(effects
				(font
					(size 1.016 1.016)
					(thickness 0.1524)
				)
			)
		)
		(property "Device Type" "R402H16"
			(at 0.064008 -5.517896 270)
			(unlocked yes)
			(layer "F.Fab")
			(hide yes)
			(effects
				(font
					(size 1.016 1.016)
					(thickness 0.1524)
				)
			)
		)
		(duplicate_pad_numbers_are_jumpers no)
		(fp_line
			(start -0.508 -0.9398)
			(end -0.508 0.9398)
			(stroke
				(width 0.1524)
				(type default)
			)
			(layer "F.SilkS")
		)
		(fp_line
			(start 0.508 -0.9398)
			(end -0.508 -0.9398)
			(stroke
				(width 0.1524)
				(type default)
			)
			(layer "F.SilkS")
		)
		(fp_rect
			(start -0.508 0.9398)
			(end 0.508 -0.9398)
			(stroke
				(width 0)
				(type default)
			)
			(fill no)
			(layer "F.CrtYd")
		)
		(fp_rect
			(start -0.508 0.9398)
			(end 0.508 -0.9398)
			(stroke
				(width 0)
				(type default)
			)
			(fill no)
			(layer "F.Fab")
		)
		(pad "1" smd custom
			(at 0 -0.4445 270)
			(size 0.1397 0.1397)
			(layers "F.Cu" "F.Mask" "F.Paste")
			(net "RTC_I2C_SDA")
			(options
				(clearance outline)
				(anchor circle)
			)
			(primitives
				(gr_poly
					(pts
						(arc
							(start -0.1778 -0.2794)
							(mid -0.249642 -0.249642)
							(end -0.2794 -0.1778)
						)
						(arc
							(start -0.2794 0.1778)
							(mid -0.249642 0.249642)
							(end -0.1778 0.2794)
						)
						(arc
							(start 0.1778 0.2794)
							(mid 0.249642 0.249642)
							(end 0.2794 0.1778)
						)
						(arc
							(start 0.2794 -0.1778)
							(mid 0.249642 -0.249642)
							(end 0.1778 -0.2794)
						)
					)
					(width 0)
					(fill yes)
				)
			)
		)
		(pad "2" smd custom
			(at 0 0.4445 270)
			(size 0.1397 0.1397)
			(layers "F.Cu" "F.Mask" "F.Paste")
			(net "BMC_I2C_A_SDA")
			(options
				(clearance outline)
				(anchor circle)
			)
			(primitives
				(gr_poly
					(pts
						(arc
							(start -0.1778 -0.2794)
							(mid -0.249642 -0.249642)
							(end -0.2794 -0.1778)
						)
						(arc
							(start -0.2794 0.1778)
							(mid -0.249642 0.249642)
							(end -0.1778 0.2794)
						)
						(arc
							(start 0.1778 0.2794)
							(mid 0.249642 0.249642)
							(end 0.2794 0.1778)
						)
						(arc
							(start 0.2794 -0.1778)
							(mid 0.249642 -0.249642)
							(end 0.1778 -0.2794)
						)
					)
					(width 0)
					(fill yes)
				)
			)
		)
	)
	(footprint ""
		(layer "F.Cu")
		(at 133.736842 -83.891882 90)
		(property "Reference" "SC1095"
			(at 0 0 90)
			(layer "F.SilkS")
			(hide yes)
			(effects
				(font
					(size 1.27 1.27)
				)
			)
		)
		(property "Value" "SCD01U10V1KX-GP"
			(at -2.8321 -1.7399 90)
			(unlocked yes)
			(layer "F.Fab")
			(hide yes)
			(effects
				(font
					(size 1.016 1.016)
					(thickness 0.1524)
				)
			)
		)
		(property "Device Type" "C0201H13"
			(at -2.8321 -3.2639 90)
			(unlocked yes)
			(layer "F.Fab")
			(hide yes)
			(effects
				(font
					(size 1.016 1.016)
					(thickness 0.1524)
				)
			)
		)
		(duplicate_pad_numbers_are_jumpers no)
		(fp_rect
			(start -0.2794 0.6477)
			(end 0.2794 -0.6477)
			(stroke
				(width 0)
				(type default)
			)
			(fill no)
			(layer "F.CrtYd")
		)
		(fp_rect
			(start -0.2794 0.6477)
			(end 0.2794 -0.6477)
			(stroke
				(width 0)
				(type default)
			)
			(fill no)
			(layer "F.Fab")
		)
		(pad "1" smd custom
			(at 0 -0.2794 90)
			(size 0.0762 0.0762)
			(layers "F.Cu" "F.Mask" "F.Paste")
			(net "SAS_HDD_TX14_N")
			(options
				(clearance outline)
				(anchor circle)
			)
			(primitives
				(gr_poly
					(pts
						(arc
							(start 0.1524 -0.127)
							(mid 0.137521 -0.162921)
							(end 0.1016 -0.1778)
						)
						(arc
							(start -0.1016 -0.1778)
							(mid -0.137521 -0.162921)
							(end -0.1524 -0.127)
						)
						(arc
							(start -0.1524 0.127)
							(mid -0.137521 0.162921)
							(end -0.1016 0.1778)
						)
						(arc
							(start 0.1016 0.1778)
							(mid 0.137521 0.162921)
							(end 0.1524 0.127)
						)
					)
					(width 0)
					(fill yes)
				)
			)
		)
		(pad "2" smd custom
			(at 0 0.2794 90)
			(size 0.0762 0.0762)
			(layers "F.Cu" "F.Mask" "F.Paste")
			(net "3008_SAS_RX_N2")
			(options
				(clearance outline)
				(anchor circle)
			)
			(primitives
				(gr_poly
					(pts
						(arc
							(start 0.1524 -0.127)
							(mid 0.137521 -0.162921)
							(end 0.1016 -0.1778)
						)
						(arc
							(start -0.1016 -0.1778)
							(mid -0.137521 -0.162921)
							(end -0.1524 -0.127)
						)
						(arc
							(start -0.1524 0.127)
							(mid -0.137521 0.162921)
							(end -0.1016 0.1778)
						)
						(arc
							(start 0.1016 0.1778)
							(mid 0.137521 0.162921)
							(end 0.1524 0.127)
						)
					)
					(width 0)
					(fill yes)
				)
			)
		)
	)
	(footprint ""
		(layer "F.Cu")
		(at 91.186 -10.033 180)
		(property "Reference" "PC201"
			(at 0 0 180)
			(layer "F.SilkS")
			(hide yes)
			(effects
				(font
					(size 1.27 1.27)
				)
			)
		)
		(property "Value" "SC22U6D3V6KX-2-GP"
			(at -0.0762 -5.1308 180)
			(unlocked yes)
			(layer "F.Fab")
			(hide yes)
			(effects
				(font
					(size 1.016 1.016)
					(thickness 0.1524)
				)
			)
		)
		(property "Device Type" "C1206H71"
			(at -0.127 -6.6548 180)
			(unlocked yes)
			(layer "F.Fab")
			(hide yes)
			(effects
				(font
					(size 1.016 1.016)
					(thickness 0.1524)
				)
			)
		)
		(duplicate_pad_numbers_are_jumpers no)
		(fp_line
			(start 1.016 2.2352)
			(end -1.016 2.2352)
			(stroke
				(width 0.1524)
				(type default)
			)
			(layer "F.SilkS")
		)
		(fp_line
			(start 1.016 0.8382)
			(end 1.016 2.2352)
			(stroke
				(width 0.1524)
				(type default)
			)
			(layer "F.SilkS")
		)
		(fp_line
			(start 1.016 -2.2352)
			(end 1.016 -0.8382)
			(stroke
				(width 0.1524)
				(type default)
			)
			(layer "F.SilkS")
		)
		(fp_line
			(start -1.016 2.2352)
			(end -1.016 0.8382)
			(stroke
				(width 0.1524)
				(type default)
			)
			(layer "F.SilkS")
		)
		(fp_line
			(start -1.016 -0.8382)
			(end -1.016 -2.2352)
			(stroke
				(width 0.1524)
				(type default)
			)
			(layer "F.SilkS")
		)
		(fp_line
			(start -1.016 -2.2352)
			(end 1.016 -2.2352)
			(stroke
				(width 0.1524)
				(type default)
			)
			(layer "F.SilkS")
		)
		(fp_rect
			(start -1.0922 2.3114)
			(end 1.0922 -2.3114)
			(stroke
				(width 0)
				(type default)
			)
			(fill no)
			(layer "F.CrtYd")
		)
		(fp_poly
			(pts
				(xy 1.0922 -2.3114) (xy 1.0922 2.3114) (xy -1.0922 2.3114) (xy -1.0922 -2.3114)
			)
			(stroke
				(width 0)
				(type default)
			)
			(fill no)
			(layer "F.Fab")
		)
		(pad "1" smd rect
			(at 0 -1.397 180)
			(size 1.651 1.27)
			(layers "F.Cu" "F.Mask" "F.Paste")
			(net "P0V955_C")
		)
		(pad "2" smd rect
			(at 0 1.397 180)
			(size 1.651 1.27)
			(layers "F.Cu" "F.Mask" "F.Paste")
			(net "GND")
		)
	)
)
